(kicad_pcb
	(version 20241229)
	(generator "pcbnew")
	(generator_version "9.0")
	(general
		(thickness 1.62)
		(legacy_teardrops no)
	)
	(paper "A3")
	(title_block
		(title "COM Express 7 Baseboard")
		(date "2025-02-04")
		(rev "1.1.2")
		(company "Antmicro Ltd")
		(comment 1 "www.antmicro.com")
		(comment 9 "footprints 775-780 of 802")
	)
	(layers
		(0 "F.Cu" signal)
		(4 "In1.Cu" signal)
		(6 "In2.Cu" signal)
		(8 "In3.Cu" signal)
		(10 "In4.Cu" signal)
		(12 "In5.Cu" signal)
		(14 "In6.Cu" signal)
		(2 "B.Cu" signal)
		(9 "F.Adhes" user "F.Adhesive")
		(11 "B.Adhes" user "B.Adhesive")
		(13 "F.Paste" user)
		(15 "B.Paste" user)
		(5 "F.SilkS" user "F.Silkscreen")
		(7 "B.SilkS" user "B.Silkscreen")
		(1 "F.Mask" user)
		(3 "B.Mask" user)
		(17 "Dwgs.User" user "User.Drawings")
		(19 "Cmts.User" user "User.Comments")
		(21 "Eco1.User" user "User.Eco1")
		(23 "Eco2.User" user "User.Eco2")
		(25 "Edge.Cuts" user)
		(27 "Margin" user)
		(31 "F.CrtYd" user "F.Courtyard")
		(29 "B.CrtYd" user "B.Courtyard")
		(35 "F.Fab" user)
		(33 "B.Fab" user)
	)
	(footprint "antmicro-footprints:TP_SMD_0.75mm"
		(layer "B.Cu")
		(at 193.607538 150.457538 -45)
		(property "Reference" "TP17"
			(at -0.488908 -0.742463 45)
			(layer "B.SilkS")
			(effects
				(font
					(size 0.7 0.7)
					(thickness 0.15)
				)
				(justify right top mirror)
			)
		)
		(property "Value" "TP_0.75mm_SMD"
			(at 3.225 -53.865 135)
			(layer "B.Fab")
			(hide yes)
			(effects
				(font
					(size 0.7 0.7)
					(thickness 0.15)
				)
				(justify left bottom mirror)
			)
		)
		(property "Author" "Antmicro"
			(at 430.7 339.52 135)
			(layer "B.Fab")
			(hide yes)
			(effects
				(font
					(size 1 1)
					(thickness 0.15)
				)
				(justify mirror)
			)
		)
		(property "License" "Apache-2.0"
			(at 430.7 339.52 135)
			(layer "B.Fab")
			(hide yes)
			(effects
				(font
					(size 1 1)
					(thickness 0.15)
				)
				(justify mirror)
			)
		)
		(property "MPN" ""
			(at 430.7 339.52 135)
			(layer "B.Fab")
			(hide yes)
			(effects
				(font
					(size 1 1)
					(thickness 0.15)
				)
				(justify mirror)
			)
		)
		(property "Manufacturer" ""
			(at 430.7 339.52 135)
			(layer "B.Fab")
			(hide yes)
			(effects
				(font
					(size 1 1)
					(thickness 0.15)
				)
				(justify mirror)
			)
		)
		(property "Public" "False"
			(at 430.7 339.52 135)
			(layer "B.Fab")
			(hide yes)
			(effects
				(font
					(size 1 1)
					(thickness 0.15)
				)
				(justify mirror)
			)
		)
		(sheetname "Com Express 7 Interfaces")
		(sheetfile "com_express_7_interfaces.kicad_sch")
		(attr exclude_from_pos_files exclude_from_bom)
		(fp_circle
			(center 0 0)
			(end 0.475 0)
			(stroke
				(width 0.05)
				(type default)
			)
			(fill no)
			(layer "B.CrtYd")
		)
		(pad "1" smd circle
			(at 0 0 315)
			(size 0.75 0.75)
			(layers "B.Cu" "B.Mask")
			(net 484 "Net-(J12K-10G_PHY_CAP_01)")
			(pinfunction "1")
			(pintype "passive")
			(teardrops
				(best_length_ratio 0.4)
				(max_length 1)
				(best_width_ratio 0.9)
				(max_width 2)
				(curved_edges yes)
				(filter_ratio 0.9)
				(enabled yes)
				(allow_two_segments yes)
				(prefer_zone_connections yes)
			)
		)
	)
	(footprint "antmicro-footprints:TP_SMD_0.75mm"
		(layer "B.Cu")
		(at 158.9 162.46 -90)
		(property "Reference" "TP2"
			(at -2.437 -0.449 90)
			(layer "B.SilkS")
			(effects
				(font
					(size 0.7 0.7)
					(thickness 0.15)
				)
				(justify left bottom mirror)
			)
		)
		(property "Value" "TP_0.75mm_SMD"
			(at 0 -1.2 90)
			(layer "B.Fab")
			(effects
				(font
					(size 0.7 0.7)
					(thickness 0.15)
				)
				(justify left bottom mirror)
			)
		)
		(property "Author" "Antmicro"
			(at -3.56 321.36 0)
			(layer "B.Fab")
			(hide yes)
			(effects
				(font
					(size 1 1)
					(thickness 0.15)
				)
				(justify mirror)
			)
		)
		(property "License" "Apache-2.0"
			(at -3.56 321.36 0)
			(layer "B.Fab")
			(hide yes)
			(effects
				(font
					(size 1 1)
					(thickness 0.15)
				)
				(justify mirror)
			)
		)
		(property "MPN" ""
			(at -3.56 321.36 0)
			(layer "B.Fab")
			(hide yes)
			(effects
				(font
					(size 1 1)
					(thickness 0.15)
				)
				(justify mirror)
			)
		)
		(property "Manufacturer" ""
			(at -3.56 321.36 0)
			(layer "B.Fab")
			(hide yes)
			(effects
				(font
					(size 1 1)
					(thickness 0.15)
				)
				(justify mirror)
			)
		)
		(property "Public" "False"
			(at -3.56 321.36 0)
			(layer "B.Fab")
			(hide yes)
			(effects
				(font
					(size 1 1)
					(thickness 0.15)
				)
				(justify mirror)
			)
		)
		(sheetname "2xSFP+")
		(sheetfile "2xSFP+.kicad_sch")
		(attr exclude_from_pos_files exclude_from_bom)
		(fp_circle
			(center 0 0)
			(end 0.475 0)
			(stroke
				(width 0.05)
				(type default)
			)
			(fill no)
			(layer "B.CrtYd")
		)
		(pad "1" smd circle
			(at 0 0 270)
			(size 0.75 0.75)
			(layers "B.Cu" "B.Mask")
			(net 698 "Net-(U5-IO0_7)")
			(pinfunction "1")
			(pintype "passive")
			(teardrops
				(best_length_ratio 0.4)
				(max_length 1)
				(best_width_ratio 0.9)
				(max_width 2)
				(curved_edges yes)
				(filter_ratio 0.9)
				(enabled yes)
				(allow_two_segments yes)
				(prefer_zone_connections yes)
			)
		)
	)
	(footprint "antmicro-footprints:R_0402_1005Metric"
		(layer "B.Cu")
		(at 104.44 169.96)
		(descr "Resistor SMD 0402")
		(tags "resistor SMD 0402")
		(property "Reference" "R80"
			(at -1.1 1.35 0)
			(layer "B.SilkS")
			(effects
				(font
					(size 0.7 0.7)
					(thickness 0.15)
				)
				(justify right bottom mirror)
			)
		)
		(property "Value" "R_0R_0402"
			(at -1.011843 -1.772047 0)
			(layer "B.Fab")
			(effects
				(font
					(size 0.7 0.7)
					(thickness 0.15)
				)
				(justify right bottom mirror)
			)
		)
		(property "Datasheet" "https://industrial.panasonic.com/cdbs/www-data/pdf/RDA0000/AOA0000C301.pdf"
			(at 0 0 0)
			(layer "F.Fab")
			(hide yes)
			(effects
				(font
					(size 1.27 1.27)
					(thickness 0.15)
				)
			)
		)
		(property "Author" "Antmicro"
			(at 0 0 0)
			(layer "B.Fab")
			(hide yes)
			(effects
				(font
					(size 1 1)
					(thickness 0.15)
				)
				(justify mirror)
			)
		)
		(property "Current" "1A"
			(at 0 0 0)
			(layer "B.Fab")
			(hide yes)
			(effects
				(font
					(size 1 1)
					(thickness 0.15)
				)
				(justify mirror)
			)
		)
		(property "License" "Apache-2.0"
			(at 0 0 0)
			(layer "B.Fab")
			(hide yes)
			(effects
				(font
					(size 1 1)
					(thickness 0.15)
				)
				(justify mirror)
			)
		)
		(property "MPN" "ERJ2GE0R00X"
			(at 0 0 0)
			(layer "B.Fab")
			(hide yes)
			(effects
				(font
					(size 1 1)
					(thickness 0.15)
				)
				(justify mirror)
			)
		)
		(property "Manufacturer" "Panasonic"
			(at 0 0 0)
			(layer "B.Fab")
			(hide yes)
			(effects
				(font
					(size 1 1)
					(thickness 0.15)
				)
				(justify mirror)
			)
		)
		(property "Public" "False"
			(at 0 0 0)
			(layer "B.Fab")
			(hide yes)
			(effects
				(font
					(size 1 1)
					(thickness 0.15)
				)
				(justify mirror)
			)
		)
		(property "Tolerance" ""
			(at 0 0 0)
			(layer "B.Fab")
			(hide yes)
			(effects
				(font
					(size 1 1)
					(thickness 0.15)
				)
				(justify mirror)
			)
		)
		(property "Val" "0R"
			(at 0 0 0)
			(layer "B.Fab")
			(hide yes)
			(effects
				(font
					(size 1 1)
					(thickness 0.15)
				)
				(justify mirror)
			)
		)
		(sheetname "OCuLink")
		(sheetfile "oculink.kicad_sch")
		(attr smd)
		(fp_rect
			(start -0.925 0.47)
			(end 0.925 -0.47)
			(stroke
				(width 0.05)
				(type default)
			)
			(fill no)
			(layer "B.CrtYd")
		)
		(fp_rect
			(start -0.5 0.25)
			(end 0.5 -0.25)
			(stroke
				(width 0.15)
				(type solid)
			)
			(fill no)
			(layer "B.Fab")
		)
		(pad "1" smd roundrect
			(at -0.48 0)
			(size 0.59 0.64)
			(layers "B.Cu" "B.Mask" "B.Paste")
			(roundrect_rratio 0.25)
			(net 60 "/OCuLink/V_{ACT_RX}0")
			(pintype "passive")
			(teardrops
				(best_length_ratio 0.2)
				(max_length 1)
				(best_width_ratio 0.9)
				(max_width 2)
				(curved_edges yes)
				(filter_ratio 0.9)
				(enabled yes)
				(allow_two_segments yes)
				(prefer_zone_connections yes)
			)
		)
		(pad "2" smd roundrect
			(at 0.48 0)
			(size 0.59 0.64)
			(layers "B.Cu" "B.Mask" "B.Paste")
			(roundrect_rratio 0.25)
			(net 2 "+3V3")
			(pintype "passive")
			(teardrops
				(best_length_ratio 0.2)
				(max_length 1)
				(best_width_ratio 0.9)
				(max_width 2)
				(curved_edges yes)
				(filter_ratio 0.9)
				(enabled yes)
				(allow_two_segments yes)
				(prefer_zone_connections yes)
			)
		)
	)
	(footprint "antmicro-footprints:C_0402_1005Metric"
		(layer "B.Cu")
		(at 151.45 136.36 -90)
		(descr "Capacitor SMD 0402")
		(tags "capacitor SMD 0402")
		(property "Reference" "C174"
			(at -1.1 -1.4 90)
			(layer "B.SilkS")
			(effects
				(font
					(size 0.7 0.7)
					(thickness 0.15)
				)
				(justify left bottom mirror)
			)
		)
		(property "Value" "C_100n_0402"
			(at -1.022927 -2.155213 90)
			(layer "B.Fab")
			(effects
				(font
					(size 0.7 0.7)
					(thickness 0.15)
				)
				(justify left bottom mirror)
			)
		)
		(property "Datasheet" "https://www.murata.com/products/productdetail?partno=GRM155R61H104KE14%23"
			(at 0 0 270)
			(layer "F.Fab")
			(hide yes)
			(effects
				(font
					(size 1.27 1.27)
					(thickness 0.15)
				)
			)
		)
		(property "Author" "Antmicro"
			(at 15.09 287.81 0)
			(layer "B.Fab")
			(hide yes)
			(effects
				(font
					(size 1 1)
					(thickness 0.15)
				)
				(justify mirror)
			)
		)
		(property "Dielectric" "X5R"
			(at 15.09 287.81 0)
			(layer "B.Fab")
			(hide yes)
			(effects
				(font
					(size 1 1)
					(thickness 0.15)
				)
				(justify mirror)
			)
		)
		(property "License" "Apache-2.0"
			(at 15.09 287.81 0)
			(layer "B.Fab")
			(hide yes)
			(effects
				(font
					(size 1 1)
					(thickness 0.15)
				)
				(justify mirror)
			)
		)
		(property "MPN" "GRM155R61H104KE14D"
			(at 15.09 287.81 0)
			(layer "B.Fab")
			(hide yes)
			(effects
				(font
					(size 1 1)
					(thickness 0.15)
				)
				(justify mirror)
			)
		)
		(property "Manufacturer" "Murata"
			(at 15.09 287.81 0)
			(layer "B.Fab")
			(hide yes)
			(effects
				(font
					(size 1 1)
					(thickness 0.15)
				)
				(justify mirror)
			)
		)
		(property "Public" "False"
			(at 15.09 287.81 0)
			(layer "B.Fab")
			(hide yes)
			(effects
				(font
					(size 1 1)
					(thickness 0.15)
				)
				(justify mirror)
			)
		)
		(property "Val" "100n"
			(at 15.09 287.81 0)
			(layer "B.Fab")
			(hide yes)
			(effects
				(font
					(size 1 1)
					(thickness 0.15)
				)
				(justify mirror)
			)
		)
		(property "Voltage" "50V"
			(at 15.09 287.81 0)
			(layer "B.Fab")
			(hide yes)
			(effects
				(font
					(size 1 1)
					(thickness 0.15)
				)
				(justify mirror)
			)
		)
		(sheetname "KR to SFI #1")
		(sheetfile "kr_sfi.kicad_sch")
		(attr smd)
		(fp_rect
			(start -0.925 0.47)
			(end 0.925 -0.47)
			(stroke
				(width 0.05)
				(type default)
			)
			(fill no)
			(layer "B.CrtYd")
		)
		(fp_line
			(start -0.494 0.25)
			(end -0.494 -0.248)
			(stroke
				(width 0.15)
				(type solid)
			)
			(layer "B.Fab")
		)
		(fp_line
			(start 0.504 0.25)
			(end -0.494 0.25)
			(stroke
				(width 0.15)
				(type solid)
			)
			(layer "B.Fab")
		)
		(fp_line
			(start -0.494 -0.248)
			(end 0.504 -0.248)
			(stroke
				(width 0.15)
				(type solid)
			)
			(layer "B.Fab")
		)
		(fp_line
			(start 0.504 -0.248)
			(end 0.504 0.25)
			(stroke
				(width 0.15)
				(type solid)
			)
			(layer "B.Fab")
		)
		(pad "1" smd roundrect
			(at -0.48 0 270)
			(size 0.59 0.64)
			(layers "B.Cu" "B.Mask" "B.Paste")
			(roundrect_rratio 0.25)
			(net 1 "GND")
			(pintype "passive")
			(teardrops
				(best_length_ratio 0.2)
				(max_length 1)
				(best_width_ratio 0.9)
				(max_width 2)
				(curved_edges yes)
				(filter_ratio 0.9)
				(enabled yes)
				(allow_two_segments yes)
				(prefer_zone_connections yes)
			)
		)
		(pad "2" smd roundrect
			(at 0.48 0 270)
			(size 0.59 0.64)
			(layers "B.Cu" "B.Mask" "B.Paste")
			(roundrect_rratio 0.25)
			(net 74 "+1V0")
			(pintype "passive")
			(teardrops
				(best_length_ratio 0.2)
				(max_length 1)
				(best_width_ratio 0.9)
				(max_width 2)
				(curved_edges yes)
				(filter_ratio 0.9)
				(enabled yes)
				(allow_two_segments yes)
				(prefer_zone_connections yes)
			)
		)
	)
	(footprint "antmicro-footprints:R_0402_1005Metric"
		(layer "B.Cu")
		(at 139.74 140.36)
		(descr "Resistor SMD 0402")
		(tags "resistor SMD 0402")
		(property "Reference" "R286"
			(at -3.64 0.75 0)
			(layer "B.SilkS")
			(effects
				(font
					(size 0.7 0.7)
					(thickness 0.15)
				)
				(justify right bottom mirror)
			)
		)
		(property "Value" "R_10k_0402"
			(at -1.011843 -1.772047 0)
			(layer "B.Fab")
			(effects
				(font
					(size 0.7 0.7)
					(thickness 0.15)
				)
				(justify right bottom mirror)
			)
		)
		(property "Datasheet" "https://www.bourns.com/docs/product-datasheets/cr.pdf"
			(at 0 0 0)
			(layer "F.Fab")
			(hide yes)
			(effects
				(font
					(size 1.27 1.27)
					(thickness 0.15)
				)
			)
		)
		(property "Author" "Antmicro"
			(at 0 0 0)
			(layer "B.Fab")
			(hide yes)
			(effects
				(font
					(size 1 1)
					(thickness 0.15)
				)
				(justify mirror)
			)
		)
		(property "License" "Apache-2.0"
			(at 0 0 0)
			(layer "B.Fab")
			(hide yes)
			(effects
				(font
					(size 1 1)
					(thickness 0.15)
				)
				(justify mirror)
			)
		)
		(property "MPN" "CR0402-FX-1002GLF"
			(at 0 0 0)
			(layer "B.Fab")
			(hide yes)
			(effects
				(font
					(size 1 1)
					(thickness 0.15)
				)
				(justify mirror)
			)
		)
		(property "Manufacturer" "Bourns"
			(at 0 0 0)
			(layer "B.Fab")
			(hide yes)
			(effects
				(font
					(size 1 1)
					(thickness 0.15)
				)
				(justify mirror)
			)
		)
		(property "Public" "False"
			(at 0 0 0)
			(layer "B.Fab")
			(hide yes)
			(effects
				(font
					(size 1 1)
					(thickness 0.15)
				)
				(justify mirror)
			)
		)
		(property "Tolerance" "1%"
			(at 0 0 0)
			(layer "B.Fab")
			(hide yes)
			(effects
				(font
					(size 1 1)
					(thickness 0.15)
				)
				(justify mirror)
			)
		)
		(property "Val" "10k"
			(at 0 0 0)
			(layer "B.Fab")
			(hide yes)
			(effects
				(font
					(size 1 1)
					(thickness 0.15)
				)
				(justify mirror)
			)
		)
		(sheetname "KR to SFI #2")
		(sheetfile "kr_sfi.kicad_sch")
		(attr smd dnp)
		(fp_rect
			(start -0.925 0.47)
			(end 0.925 -0.47)
			(stroke
				(width 0.05)
				(type default)
			)
			(fill no)
			(layer "B.CrtYd")
		)
		(fp_rect
			(start -0.5 0.25)
			(end 0.5 -0.25)
			(stroke
				(width 0.15)
				(type solid)
			)
			(fill no)
			(layer "B.Fab")
		)
		(pad "1" smd roundrect
			(at -0.48 0)
			(size 0.59 0.64)
			(layers "B.Cu" "B.Mask" "B.Paste")
			(roundrect_rratio 0.25)
			(net 673 "/2xSFP+/KR to SFI #2/PRBSEN")
			(pintype "passive")
			(teardrops
				(best_length_ratio 0.2)
				(max_length 1)
				(best_width_ratio 0.9)
				(max_width 2)
				(curved_edges yes)
				(filter_ratio 0.9)
				(enabled yes)
				(allow_two_segments yes)
				(prefer_zone_connections yes)
			)
		)
		(pad "2" smd roundrect
			(at 0.48 0)
			(size 0.59 0.64)
			(layers "B.Cu" "B.Mask" "B.Paste")
			(roundrect_rratio 0.25)
			(net 78 "+1V8")
			(pintype "passive")
			(teardrops
				(best_length_ratio 0.2)
				(max_length 1)
				(best_width_ratio 0.9)
				(max_width 2)
				(curved_edges yes)
				(filter_ratio 0.9)
				(enabled yes)
				(allow_two_segments yes)
				(prefer_zone_connections yes)
			)
		)
	)
	(footprint "antmicro-footprints:R_0402_1005Metric"
		(layer "B.Cu")
		(at 126.09 142.06)
		(descr "Resistor SMD 0402")
		(tags "resistor SMD 0402")
		(property "Reference" "R303"
			(at -3.64 1.05 0)
			(layer "B.SilkS")
			(effects
				(font
					(size 0.7 0.7)
					(thickness 0.15)
				)
				(justify right bottom mirror)
			)
		)
		(property "Value" "R_10k_0402"
			(at -1.011843 -1.772047 0)
			(layer "B.Fab")
			(effects
				(font
					(size 0.7 0.7)
					(thickness 0.15)
				)
				(justify right bottom mirror)
			)
		)
		(property "Datasheet" "https://www.bourns.com/docs/product-datasheets/cr.pdf"
			(at 0 0 0)
			(layer "F.Fab")
			(hide yes)
			(effects
				(font
					(size 1.27 1.27)
					(thickness 0.15)
				)
			)
		)
		(property "Author" "Antmicro"
			(at 0 0 0)
			(layer "B.Fab")
			(hide yes)
			(effects
				(font
					(size 1 1)
					(thickness 0.15)
				)
				(justify mirror)
			)
		)
		(property "License" "Apache-2.0"
			(at 0 0 0)
			(layer "B.Fab")
			(hide yes)
			(effects
				(font
					(size 1 1)
					(thickness 0.15)
				)
				(justify mirror)
			)
		)
		(property "MPN" "CR0402-FX-1002GLF"
			(at 0 0 0)
			(layer "B.Fab")
			(hide yes)
			(effects
				(font
					(size 1 1)
					(thickness 0.15)
				)
				(justify mirror)
			)
		)
		(property "Manufacturer" "Bourns"
			(at 0 0 0)
			(layer "B.Fab")
			(hide yes)
			(effects
				(font
					(size 1 1)
					(thickness 0.15)
				)
				(justify mirror)
			)
		)
		(property "Public" "False"
			(at 0 0 0)
			(layer "B.Fab")
			(hide yes)
			(effects
				(font
					(size 1 1)
					(thickness 0.15)
				)
				(justify mirror)
			)
		)
		(property "Tolerance" "1%"
			(at 0 0 0)
			(layer "B.Fab")
			(hide yes)
			(effects
				(font
					(size 1 1)
					(thickness 0.15)
				)
				(justify mirror)
			)
		)
		(property "Val" "10k"
			(at 0 0 0)
			(layer "B.Fab")
			(hide yes)
			(effects
				(font
					(size 1 1)
					(thickness 0.15)
				)
				(justify mirror)
			)
		)
		(sheetname "KR to SFI #2")
		(sheetfile "kr_sfi.kicad_sch")
		(attr smd)
		(fp_rect
			(start -0.925 0.47)
			(end 0.925 -0.47)
			(stroke
				(width 0.05)
				(type default)
			)
			(fill no)
			(layer "B.CrtYd")
		)
		(fp_rect
			(start -0.5 0.25)
			(end 0.5 -0.25)
			(stroke
				(width 0.15)
				(type solid)
			)
			(fill no)
			(layer "B.Fab")
		)
		(pad "1" smd roundrect
			(at -0.48 0)
			(size 0.59 0.64)
			(layers "B.Cu" "B.Mask" "B.Paste")
			(roundrect_rratio 0.25)
			(net 1 "GND")
			(pintype "passive")
			(teardrops
				(best_length_ratio 0.2)
				(max_length 1)
				(best_width_ratio 0.9)
				(max_width 2)
				(curved_edges yes)
				(filter_ratio 0.9)
				(enabled yes)
				(allow_two_segments yes)
				(prefer_zone_connections yes)
			)
		)
		(pad "2" smd roundrect
			(at 0.48 0)
			(size 0.59 0.64)
			(layers "B.Cu" "B.Mask" "B.Paste")
			(roundrect_rratio 0.25)
			(net 683 "Net-(U45C-MODE_{SEL})")
			(pintype "passive")
			(teardrops
				(best_length_ratio 0.2)
				(max_length 1)
				(best_width_ratio 0.9)
				(max_width 2)
				(curved_edges yes)
				(filter_ratio 0.9)
				(enabled yes)
				(allow_two_segments yes)
				(prefer_zone_connections yes)
			)
		)
	)
)
